(kicad_pcb
	(version 20260206)
	(generator "pcbnew")
	(generator_version "10.0")
	(general
		(thickness 1.6)
		(legacy_teardrops no)
	)
	(paper "A4")
	(title_block
		(title "03242023_DA0F0TMBIJ0_F0T_Motherboard_J_brd_V01_OCP.brd")
		(comment 1 "Grand Teton / footprint 1952 of 6105 (J11), pads 225-291 of 291")
	)
	(layers
		(0 "F.Cu" signal "TOP")
		(4 "In1.Cu" signal "GND")
		(6 "In2.Cu" signal "IN1")
		(8 "In3.Cu" signal "GND1")
		(10 "In4.Cu" signal "IN2")
		(12 "In5.Cu" signal "GND2")
		(14 "In6.Cu" signal "IN3")
		(16 "In7.Cu" signal "GND3")
		(18 "In8.Cu" signal "VCC")
		(20 "In9.Cu" signal "VCC1")
		(22 "In10.Cu" signal "GND4")
		(24 "In11.Cu" signal "IN4")
		(26 "In12.Cu" signal "GND5")
		(28 "In13.Cu" signal "IN5")
		(30 "In14.Cu" signal "GND6")
		(32 "In15.Cu" signal "IN6")
		(34 "In16.Cu" signal "GND7")
		(2 "B.Cu" signal "BOTTOM")
		(9 "F.Adhes" user "F.Adhesive")
		(11 "B.Adhes" user "B.Adhesive")
		(13 "F.Paste" user "Package Geometry/Pastemask Top")
		(15 "B.Paste" user "Package Geometry/Pastemask Bottom")
		(5 "F.SilkS" user "Ref Des/Silkscreen Top")
		(7 "B.SilkS" user "Ref Des/Silkscreen Bottom")
		(1 "F.Mask" user "Board Geometry/Soldermask Top")
		(3 "B.Mask" user "Board Geometry/Soldermask Bottom")
		(17 "Dwgs.User" user "User.Drawings")
		(19 "Cmts.User" user "User.Comments")
		(21 "Eco1.User" user "User.Eco1")
		(23 "Eco2.User" user "User.Eco2")
		(25 "Edge.Cuts" user "Board Geometry/Outline")
		(27 "Margin" user)
		(31 "F.CrtYd" user "Package Geometry/Place Bound Top")
		(29 "B.CrtYd" user "Package Geometry/Place Bound Bottom")
		(35 "F.Fab" user "Ref Des/Assembly Top")
		(33 "B.Fab" user "Ref Des/Assembly Bottom")
	)
	(footprint ""
		(layer "F.Cu")
		(at 431.434748 -258.091686)
		(property "Reference" "J11"
			(at -3.683 -81.702148 0)
			(unlocked yes)
			(layer "F.SilkS")
			(effects
				(font
					(size 0.7874 0.5842)
					(thickness 0.1524)
				)
				(justify left)
			)
		)
		(property "Value" ""
			(at 0 0 0)
			(layer "F.Fab")
			(effects
				(font
					(size 1.27 1.27)
				)
			)
		)
		(duplicate_pad_numbers_are_jumpers no)
		(pad "225" smd rect
			(at 2.050034 9.774936 270)
			(size 0.519938 1.4986)
			(layers "F.Cu" "F.Mask" "F.Paste")
			(net "M_F_CPU0_SB_CA<5>")
		)
		(pad "226" smd rect
			(at 2.050034 10.625074 270)
			(size 0.519938 1.4986)
			(layers "F.Cu" "F.Mask" "F.Paste")
			(net "GND")
		)
		(pad "227" smd rect
			(at 2.050034 11.474958 270)
			(size 0.519938 1.4986)
			(layers "F.Cu" "F.Mask" "F.Paste")
			(net "M_F_CPU0_SB_PAR")
		)
		(pad "228" smd rect
			(at 2.050034 12.325096 270)
			(size 0.519938 1.4986)
			(layers "F.Cu" "F.Mask" "F.Paste")
			(net "GND")
		)
		(pad "229" smd rect
			(at 2.050034 13.17498 270)
			(size 0.519938 1.4986)
			(layers "F.Cu" "F.Mask" "F.Paste")
			(net "M_F_CPU0_SB_CS_N<1>")
		)
		(pad "230" smd rect
			(at 2.050034 14.025118 270)
			(size 0.519938 1.4986)
			(layers "F.Cu" "F.Mask" "F.Paste")
			(net "GND")
		)
		(pad "231" smd rect
			(at 2.050034 14.875002 270)
			(size 0.519938 1.4986)
			(layers "F.Cu" "F.Mask" "F.Paste")
			(net "TP_CHF_CPU0_DIMM1_FRU_5")
		)
		(pad "232" smd rect
			(at 2.050034 15.724886 270)
			(size 0.519938 1.4986)
			(layers "F.Cu" "F.Mask" "F.Paste")
			(net "TP_CHF_CPU0_DIMM1_FRU_6")
		)
		(pad "233" smd rect
			(at 2.050034 16.575024 270)
			(size 0.519938 1.4986)
			(layers "F.Cu" "F.Mask" "F.Paste")
			(net "GND")
		)
		(pad "234" smd rect
			(at 2.050034 17.424908 270)
			(size 0.519938 1.4986)
			(layers "F.Cu" "F.Mask" "F.Paste")
			(net "M_F_CPU0_SB_CB<6>")
		)
		(pad "235" smd rect
			(at 2.050034 18.275046 270)
			(size 0.519938 1.4986)
			(layers "F.Cu" "F.Mask" "F.Paste")
			(net "GND")
		)
		(pad "236" smd rect
			(at 2.050034 19.12493 270)
			(size 0.519938 1.4986)
			(layers "F.Cu" "F.Mask" "F.Paste")
			(net "M_F_CPU0_SB_CB<7>")
		)
		(pad "237" smd rect
			(at 2.050034 19.975068 270)
			(size 0.519938 1.4986)
			(layers "F.Cu" "F.Mask" "F.Paste")
			(net "GND")
		)
		(pad "238" smd rect
			(at 2.050034 20.824952 270)
			(size 0.519938 1.4986)
			(layers "F.Cu" "F.Mask" "F.Paste")
			(net "M_F_CPU0_SB_DQS_DN<4>")
		)
		(pad "239" smd rect
			(at 2.050034 21.67509 270)
			(size 0.519938 1.4986)
			(layers "F.Cu" "F.Mask" "F.Paste")
			(net "M_F_CPU0_SB_DQS_DP<4>")
		)
		(pad "240" smd rect
			(at 2.050034 22.524974 270)
			(size 0.519938 1.4986)
			(layers "F.Cu" "F.Mask" "F.Paste")
			(net "GND")
		)
		(pad "241" smd rect
			(at 2.050034 23.375112 270)
			(size 0.519938 1.4986)
			(layers "F.Cu" "F.Mask" "F.Paste")
			(net "M_F_CPU0_SB_CB<2>")
		)
		(pad "242" smd rect
			(at 2.050034 24.224996 270)
			(size 0.519938 1.4986)
			(layers "F.Cu" "F.Mask" "F.Paste")
			(net "GND")
		)
		(pad "243" smd rect
			(at 2.050034 25.07488 270)
			(size 0.519938 1.4986)
			(layers "F.Cu" "F.Mask" "F.Paste")
			(net "M_F_CPU0_SB_CB<3>")
		)
		(pad "244" smd rect
			(at 2.050034 25.925018 270)
			(size 0.519938 1.4986)
			(layers "F.Cu" "F.Mask" "F.Paste")
			(net "GND")
		)
		(pad "245" smd rect
			(at 2.050034 26.774902 270)
			(size 0.519938 1.4986)
			(layers "F.Cu" "F.Mask" "F.Paste")
			(net "M_F_CPU0_SB_DQ<2>")
		)
		(pad "246" smd rect
			(at 2.050034 27.62504 270)
			(size 0.519938 1.4986)
			(layers "F.Cu" "F.Mask" "F.Paste")
			(net "GND")
		)
		(pad "247" smd rect
			(at 2.050034 28.474924 270)
			(size 0.519938 1.4986)
			(layers "F.Cu" "F.Mask" "F.Paste")
			(net "M_F_CPU0_SB_DQ<3>")
		)
		(pad "248" smd rect
			(at 2.050034 29.325062 270)
			(size 0.519938 1.4986)
			(layers "F.Cu" "F.Mask" "F.Paste")
			(net "GND")
		)
		(pad "249" smd rect
			(at 2.050034 30.174946 270)
			(size 0.519938 1.4986)
			(layers "F.Cu" "F.Mask" "F.Paste")
			(net "M_F_CPU0_SB_DQS_DN<5>")
		)
		(pad "250" smd rect
			(at 2.050034 31.025084 270)
			(size 0.519938 1.4986)
			(layers "F.Cu" "F.Mask" "F.Paste")
			(net "M_F_CPU0_SB_DQS_DP<5>")
		)
		(pad "251" smd rect
			(at 2.050034 31.874968 270)
			(size 0.519938 1.4986)
			(layers "F.Cu" "F.Mask" "F.Paste")
			(net "GND")
		)
		(pad "252" smd rect
			(at 2.050034 32.725106 270)
			(size 0.519938 1.4986)
			(layers "F.Cu" "F.Mask" "F.Paste")
			(net "M_F_CPU0_SB_DQ<6>")
		)
		(pad "253" smd rect
			(at 2.050034 33.57499 270)
			(size 0.519938 1.4986)
			(layers "F.Cu" "F.Mask" "F.Paste")
			(net "GND")
		)
		(pad "254" smd rect
			(at 2.050034 34.425128 270)
			(size 0.519938 1.4986)
			(layers "F.Cu" "F.Mask" "F.Paste")
			(net "M_F_CPU0_SB_DQ<7>")
		)
		(pad "255" smd rect
			(at 2.050034 35.275012 270)
			(size 0.519938 1.4986)
			(layers "F.Cu" "F.Mask" "F.Paste")
			(net "GND")
		)
		(pad "256" smd rect
			(at 2.050034 36.124896 270)
			(size 0.519938 1.4986)
			(layers "F.Cu" "F.Mask" "F.Paste")
			(net "M_F_CPU0_SB_DQ<10>")
		)
		(pad "257" smd rect
			(at 2.050034 36.975034 270)
			(size 0.519938 1.4986)
			(layers "F.Cu" "F.Mask" "F.Paste")
			(net "GND")
		)
		(pad "258" smd rect
			(at 2.050034 37.824918 270)
			(size 0.519938 1.4986)
			(layers "F.Cu" "F.Mask" "F.Paste")
			(net "M_F_CPU0_SB_DQ<11>")
		)
		(pad "259" smd rect
			(at 2.050034 38.675056 270)
			(size 0.519938 1.4986)
			(layers "F.Cu" "F.Mask" "F.Paste")
			(net "GND")
		)
		(pad "260" smd rect
			(at 2.050034 39.52494 270)
			(size 0.519938 1.4986)
			(layers "F.Cu" "F.Mask" "F.Paste")
			(net "M_F_CPU0_SB_DQS_DN<6>")
		)
		(pad "261" smd rect
			(at 2.050034 40.375078 270)
			(size 0.519938 1.4986)
			(layers "F.Cu" "F.Mask" "F.Paste")
			(net "M_F_CPU0_SB_DQS_DP<6>")
		)
		(pad "262" smd rect
			(at 2.050034 41.224962 270)
			(size 0.519938 1.4986)
			(layers "F.Cu" "F.Mask" "F.Paste")
			(net "GND")
		)
		(pad "263" smd rect
			(at 2.050034 42.0751 270)
			(size 0.519938 1.4986)
			(layers "F.Cu" "F.Mask" "F.Paste")
			(net "M_F_CPU0_SB_DQ<14>")
		)
		(pad "264" smd rect
			(at 2.050034 42.924984 270)
			(size 0.519938 1.4986)
			(layers "F.Cu" "F.Mask" "F.Paste")
			(net "GND")
		)
		(pad "265" smd rect
			(at 2.050034 43.775122 270)
			(size 0.519938 1.4986)
			(layers "F.Cu" "F.Mask" "F.Paste")
			(net "M_F_CPU0_SB_DQ<15>")
		)
		(pad "266" smd rect
			(at 2.050034 44.625006 270)
			(size 0.519938 1.4986)
			(layers "F.Cu" "F.Mask" "F.Paste")
			(net "GND")
		)
		(pad "267" smd rect
			(at 2.050034 45.47489 270)
			(size 0.519938 1.4986)
			(layers "F.Cu" "F.Mask" "F.Paste")
			(net "M_F_CPU0_SB_DQ<18>")
		)
		(pad "268" smd rect
			(at 2.050034 46.325028 270)
			(size 0.519938 1.4986)
			(layers "F.Cu" "F.Mask" "F.Paste")
			(net "GND")
		)
		(pad "269" smd rect
			(at 2.050034 47.174912 270)
			(size 0.519938 1.4986)
			(layers "F.Cu" "F.Mask" "F.Paste")
			(net "M_F_CPU0_SB_DQ<19>")
		)
		(pad "270" smd rect
			(at 2.050034 48.02505 270)
			(size 0.519938 1.4986)
			(layers "F.Cu" "F.Mask" "F.Paste")
			(net "GND")
		)
		(pad "271" smd rect
			(at 2.050034 48.874934 270)
			(size 0.519938 1.4986)
			(layers "F.Cu" "F.Mask" "F.Paste")
			(net "M_F_CPU0_SB_DQS_DN<7>")
		)
		(pad "272" smd rect
			(at 2.050034 49.725072 270)
			(size 0.519938 1.4986)
			(layers "F.Cu" "F.Mask" "F.Paste")
			(net "M_F_CPU0_SB_DQS_DP<7>")
		)
		(pad "273" smd rect
			(at 2.050034 50.574956 270)
			(size 0.519938 1.4986)
			(layers "F.Cu" "F.Mask" "F.Paste")
			(net "GND")
		)
		(pad "274" smd rect
			(at 2.050034 51.425094 270)
			(size 0.519938 1.4986)
			(layers "F.Cu" "F.Mask" "F.Paste")
			(net "M_F_CPU0_SB_DQ<22>")
		)
		(pad "275" smd rect
			(at 2.050034 52.274978 270)
			(size 0.519938 1.4986)
			(layers "F.Cu" "F.Mask" "F.Paste")
			(net "GND")
		)
		(pad "276" smd rect
			(at 2.050034 53.125116 270)
			(size 0.519938 1.4986)
			(layers "F.Cu" "F.Mask" "F.Paste")
			(net "M_F_CPU0_SB_DQ<23>")
		)
		(pad "277" smd rect
			(at 2.050034 53.975 270)
			(size 0.519938 1.4986)
			(layers "F.Cu" "F.Mask" "F.Paste")
			(net "GND")
		)
		(pad "278" smd rect
			(at 2.050034 54.824884 270)
			(size 0.519938 1.4986)
			(layers "F.Cu" "F.Mask" "F.Paste")
			(net "M_F_CPU0_SB_DQ<26>")
		)
		(pad "279" smd rect
			(at 2.050034 55.675022 270)
			(size 0.519938 1.4986)
			(layers "F.Cu" "F.Mask" "F.Paste")
			(net "GND")
		)
		(pad "280" smd rect
			(at 2.050034 56.524906 270)
			(size 0.519938 1.4986)
			(layers "F.Cu" "F.Mask" "F.Paste")
			(net "M_F_CPU0_SB_DQ<27>")
		)
		(pad "281" smd rect
			(at 2.050034 57.375044 270)
			(size 0.519938 1.4986)
			(layers "F.Cu" "F.Mask" "F.Paste")
			(net "GND")
		)
		(pad "282" smd rect
			(at 2.050034 58.224928 270)
			(size 0.519938 1.4986)
			(layers "F.Cu" "F.Mask" "F.Paste")
			(net "M_F_CPU0_SB_DQS_DN<8>")
		)
		(pad "283" smd rect
			(at 2.050034 59.075066 270)
			(size 0.519938 1.4986)
			(layers "F.Cu" "F.Mask" "F.Paste")
			(net "M_F_CPU0_SB_DQS_DP<8>")
		)
		(pad "284" smd rect
			(at 2.050034 59.92495 270)
			(size 0.519938 1.4986)
			(layers "F.Cu" "F.Mask" "F.Paste")
			(net "GND")
		)
		(pad "285" smd rect
			(at 2.050034 60.775088 270)
			(size 0.519938 1.4986)
			(layers "F.Cu" "F.Mask" "F.Paste")
			(net "M_F_CPU0_SB_DQ<30>")
		)
		(pad "286" smd rect
			(at 2.050034 61.624972 270)
			(size 0.519938 1.4986)
			(layers "F.Cu" "F.Mask" "F.Paste")
			(net "GND")
		)
		(pad "287" smd rect
			(at 2.050034 62.47511 270)
			(size 0.519938 1.4986)
			(layers "F.Cu" "F.Mask" "F.Paste")
			(net "M_F_CPU0_SB_DQ<31>")
		)
		(pad "288" smd rect
			(at 2.050034 63.324994 270)
			(size 0.519938 1.4986)
			(layers "F.Cu" "F.Mask" "F.Paste")
			(net "GND")
		)
		(pad "G1" thru_hole oval
			(at 0 -68.97497)
			(size 2.8194 1.5748)
			(drill oval 2.4384 1.1938)
			(layers "*.Cu" "*.Mask")
			(remove_unused_layers no)
			(net "GND")
			(clearance 0.127)
			(thermal_gap 0.127)
		)
		(pad "G2" thru_hole oval
			(at 0 3.875024)
			(size 2.8194 1.5748)
			(drill oval 2.4384 1.1938)
			(layers "*.Cu" "*.Mask")
			(remove_unused_layers no)
			(net "GND")
			(clearance 0.127)
			(thermal_gap 0.127)
		)
		(pad "G3" thru_hole oval
			(at 0 68.97497)
			(size 2.8194 1.5748)
			(drill oval 2.4384 1.1938)
			(layers "*.Cu" "*.Mask")
			(remove_unused_layers no)
			(net "GND")
			(clearance 0.127)
			(thermal_gap 0.127)
		)
	)
)
